# T6G (Grand Teton) — schematic netlist excerpt (pin names and nets, part order shuffled) for the footprints in the layout excerpt that follows; sources: Cadence DE-HDL packaged netlist, KiCad conversion of 04192023_DAF0TMB3IC0_F0TG_MB_C_brd_V02_OCP.brd

C1066  Q_CAP  0.1UF 10V 10% X7S  pkg C0201  page 186 : A = P3V3_AUX ; B = GND
R1155  Q_RES  33 5% EMPTY  pkg 0402LF  page 161 : A = SMB_APML_CPU0_R_SDA ; B = SMB_APML_CPU0_SDA
C661  Q_CAP  10UF 6.3V 20% X6S  pkg C0402  page 290 : A = P0V9_CPU0_RT1_2A ; B = GND

(kicad_pcb
	(version 20260206)
	(generator "pcbnew")
	(generator_version "10.0")
	(general
		(thickness 1.6)
		(legacy_teardrops no)
	)
	(paper "A4")
	(title_block
		(title "04192023_DAF0TMB3IC0_F0TG_MB_C_brd_V02_OCP.brd")
		(comment 1 "Grand Teton / footprints 7695-7697 of 8354")
	)
	(layers
		(0 "F.Cu" signal "TOP")
		(4 "In1.Cu" signal "GND")
		(6 "In2.Cu" signal "IN1")
		(8 "In3.Cu" signal "GND1")
		(10 "In4.Cu" signal "IN2")
		(12 "In5.Cu" signal "GND2")
		(14 "In6.Cu" signal "IN3")
		(16 "In7.Cu" signal "GND3")
		(18 "In8.Cu" signal "VCC")
		(20 "In9.Cu" signal "VCC1")
		(22 "In10.Cu" signal "GND4")
		(24 "In11.Cu" signal "IN4")
		(26 "In12.Cu" signal "GND5")
		(28 "In13.Cu" signal "IN5")
		(30 "In14.Cu" signal "GND6")
		(32 "In15.Cu" signal "IN6")
		(34 "In16.Cu" signal "GND7")
		(2 "B.Cu" signal "BOTTOM")
		(9 "F.Adhes" user "F.Adhesive")
		(11 "B.Adhes" user "B.Adhesive")
		(13 "F.Paste" user "Package Geometry/Pastemask Top")
		(15 "B.Paste" user "Package Geometry/Pastemask Bottom")
		(5 "F.SilkS" user "Ref Des/Silkscreen Top")
		(7 "B.SilkS" user "Ref Des/Silkscreen Bottom")
		(1 "F.Mask" user "Board Geometry/Soldermask Top")
		(3 "B.Mask" user "Board Geometry/Soldermask Bottom")
		(17 "Dwgs.User" user "User.Drawings")
		(19 "Cmts.User" user "User.Comments")
		(21 "Eco1.User" user "User.Eco1")
		(23 "Eco2.User" user "User.Eco2")
		(25 "Edge.Cuts" user "Board Geometry/Outline")
		(27 "Margin" user)
		(31 "F.CrtYd" user "Package Geometry/Place Bound Top")
		(29 "B.CrtYd" user "Package Geometry/Place Bound Bottom")
		(35 "F.Fab" user "Ref Des/Assembly Top")
		(33 "B.Fab" user "Ref Des/Assembly Bottom")
	)
	(footprint ""
		(layer "B.Cu")
		(at 237.617 -248.285)
		(property "Reference" "R1155"
			(at 0 0 0)
			(layer "B.SilkS")
			(hide yes)
			(effects
				(font
					(size 1.27 1.27)
				)
				(justify mirror)
			)
		)
		(property "Value" ""
			(at 0 0 0)
			(layer "B.Fab")
			(effects
				(font
					(size 1.27 1.27)
				)
				(justify mirror)
			)
		)
		(duplicate_pad_numbers_are_jumpers no)
		(fp_line
			(start -0.7874 -0.4064)
			(end -0.7874 0.4064)
			(stroke
				(width 0.1524)
				(type default)
			)
			(layer "B.SilkS")
		)
		(fp_line
			(start -0.7874 0.4064)
			(end 0.7874 0.4064)
			(stroke
				(width 0.1524)
				(type default)
			)
			(layer "B.SilkS")
		)
		(fp_line
			(start 0.7874 -0.4064)
			(end -0.7874 -0.4064)
			(stroke
				(width 0.1524)
				(type default)
			)
			(layer "B.SilkS")
		)
		(fp_line
			(start 0.7874 0.4064)
			(end 0.7874 -0.4064)
			(stroke
				(width 0.1524)
				(type default)
			)
			(layer "B.SilkS")
		)
		(fp_line
			(start -0.67945 -0.3048)
			(end -0.67945 0.3048)
			(stroke
				(width 0.1)
				(type default)
			)
			(layer "B.Fab")
		)
		(fp_line
			(start -0.67945 0.3048)
			(end -0.120396 0.3048)
			(stroke
				(width 0.1)
				(type default)
			)
			(layer "B.Fab")
		)
		(fp_line
			(start -0.12065 -0.3048)
			(end -0.67945 -0.3048)
			(stroke
				(width 0.1)
				(type default)
			)
			(layer "B.Fab")
		)
		(fp_line
			(start -0.12065 -0.2794)
			(end -0.12065 -0.3048)
			(stroke
				(width 0.1)
				(type default)
			)
			(layer "B.Fab")
		)
		(fp_line
			(start -0.120396 0.2794)
			(end 0.12065 0.2794)
			(stroke
				(width 0.1)
				(type default)
			)
			(layer "B.Fab")
		)
		(fp_line
			(start -0.120396 0.3048)
			(end -0.120396 0.2794)
			(stroke
				(width 0.1)
				(type default)
			)
			(layer "B.Fab")
		)
		(fp_line
			(start 0.12065 -0.305054)
			(end 0.12065 -0.2794)
			(stroke
				(width 0.1)
				(type default)
			)
			(layer "B.Fab")
		)
		(fp_line
			(start 0.12065 -0.2794)
			(end -0.12065 -0.2794)
			(stroke
				(width 0.1)
				(type default)
			)
			(layer "B.Fab")
		)
		(fp_line
			(start 0.12065 0.2794)
			(end 0.12065 0.3048)
			(stroke
				(width 0.1)
				(type default)
			)
			(layer "B.Fab")
		)
		(fp_line
			(start 0.12065 0.3048)
			(end 0.67945 0.3048)
			(stroke
				(width 0.1)
				(type default)
			)
			(layer "B.Fab")
		)
		(fp_line
			(start 0.67945 -0.305054)
			(end 0.12065 -0.305054)
			(stroke
				(width 0.1)
				(type default)
			)
			(layer "B.Fab")
		)
		(fp_line
			(start 0.67945 0.3048)
			(end 0.67945 -0.305054)
			(stroke
				(width 0.1)
				(type default)
			)
			(layer "B.Fab")
		)
		(pad "1" smd rect
			(at 0.40005 0)
			(size 0.4572 0.508)
			(layers "B.Cu" "B.Mask" "B.Paste")
			(net "SMB_APML_CPU0_R_SDA")
		)
		(pad "2" smd rect
			(at -0.40005 0)
			(size 0.4572 0.508)
			(layers "B.Cu" "B.Mask" "B.Paste")
			(net "SMB_APML_CPU0_SDA")
		)
	)
	(footprint ""
		(layer "B.Cu")
		(at 170.424348 -423.799 90)
		(property "Reference" "C1066"
			(at 0 0 90)
			(layer "B.SilkS")
			(hide yes)
			(effects
				(font
					(size 1.27 1.27)
				)
				(justify mirror)
			)
		)
		(property "Value" ""
			(at 0 0 90)
			(layer "B.Fab")
			(effects
				(font
					(size 1.27 1.27)
				)
				(justify mirror)
			)
		)
		(duplicate_pad_numbers_are_jumpers no)
		(fp_line
			(start 0.299974 -0.150114)
			(end -0.299974 -0.150114)
			(stroke
				(width 0.1)
				(type default)
			)
			(layer "B.Fab")
		)
		(fp_line
			(start -0.299974 -0.150114)
			(end -0.299974 0.150114)
			(stroke
				(width 0.1)
				(type default)
			)
			(layer "B.Fab")
		)
		(fp_line
			(start 0.299974 0.150114)
			(end 0.299974 -0.150114)
			(stroke
				(width 0.1)
				(type default)
			)
			(layer "B.Fab")
		)
		(fp_line
			(start -0.299974 0.150114)
			(end 0.299974 0.150114)
			(stroke
				(width 0.1)
				(type default)
			)
			(layer "B.Fab")
		)
		(pad "1" smd rect
			(at 0.2667 0 270)
			(size 0.3048 0.381)
			(layers "B.Cu" "B.Mask" "B.Paste")
			(net "P3V3_AUX")
		)
		(pad "2" smd rect
			(at -0.2667 0 270)
			(size 0.3048 0.381)
			(layers "B.Cu" "B.Mask" "B.Paste")
			(net "GND")
		)
	)
	(footprint ""
		(layer "B.Cu")
		(at 353.918774 -398.942052 90)
		(property "Reference" "C661"
			(at 0 0 90)
			(layer "B.SilkS")
			(hide yes)
			(effects
				(font
					(size 1.27 1.27)
				)
				(justify mirror)
			)
		)
		(property "Value" ""
			(at 0 0 90)
			(layer "B.Fab")
			(effects
				(font
					(size 1.27 1.27)
				)
				(justify mirror)
			)
		)
		(duplicate_pad_numbers_are_jumpers no)
		(fp_line
			(start 0.7874 -0.4064)
			(end -0.7874 -0.4064)
			(stroke
				(width 0.1524)
				(type default)
			)
			(layer "B.SilkS")
		)
		(fp_line
			(start -0.7874 -0.4064)
			(end -0.7874 0.4064)
			(stroke
				(width 0.1524)
				(type default)
			)
			(layer "B.SilkS")
		)
		(fp_line
			(start 0.7874 0.4064)
			(end 0.7874 -0.4064)
			(stroke
				(width 0.1524)
				(type default)
			)
			(layer "B.SilkS")
		)
		(fp_line
			(start -0.7874 0.4064)
			(end 0.7874 0.4064)
			(stroke
				(width 0.1524)
				(type default)
			)
			(layer "B.SilkS")
		)
		(fp_line
			(start 0.67945 -0.305054)
			(end 0.12065 -0.305054)
			(stroke
				(width 0.1)
				(type default)
			)
			(layer "B.Fab")
		)
		(fp_line
			(start 0.12065 -0.305054)
			(end 0.12065 -0.2794)
			(stroke
				(width 0.1)
				(type default)
			)
			(layer "B.Fab")
		)
		(fp_line
			(start -0.12065 -0.3048)
			(end -0.67945 -0.3048)
			(stroke
				(width 0.1)
				(type default)
			)
			(layer "B.Fab")
		)
		(fp_line
			(start -0.67945 -0.3048)
			(end -0.67945 0.3048)
			(stroke
				(width 0.1)
				(type default)
			)
			(layer "B.Fab")
		)
		(fp_line
			(start 0.12065 -0.2794)
			(end -0.12065 -0.2794)
			(stroke
				(width 0.1)
				(type default)
			)
			(layer "B.Fab")
		)
		(fp_line
			(start -0.12065 -0.2794)
			(end -0.12065 -0.3048)
			(stroke
				(width 0.1)
				(type default)
			)
			(layer "B.Fab")
		)
		(fp_line
			(start 0.12065 0.2794)
			(end 0.12065 0.3048)
			(stroke
				(width 0.1)
				(type default)
			)
			(layer "B.Fab")
		)
		(fp_line
			(start -0.120396 0.2794)
			(end 0.12065 0.2794)
			(stroke
				(width 0.1)
				(type default)
			)
			(layer "B.Fab")
		)
		(fp_line
			(start 0.67945 0.3048)
			(end 0.67945 -0.305054)
			(stroke
				(width 0.1)
				(type default)
			)
			(layer "B.Fab")
		)
		(fp_line
			(start 0.12065 0.3048)
			(end 0.67945 0.3048)
			(stroke
				(width 0.1)
				(type default)
			)
			(layer "B.Fab")
		)
		(fp_line
			(start -0.120396 0.3048)
			(end -0.120396 0.2794)
			(stroke
				(width 0.1)
				(type default)
			)
			(layer "B.Fab")
		)
		(fp_line
			(start -0.67945 0.3048)
			(end -0.120396 0.3048)
			(stroke
				(width 0.1)
				(type default)
			)
			(layer "B.Fab")
		)
		(pad "1" smd circle
			(at 0.40005 0 270)
			(size 0 0)
			(layers "B.Cu" "B.Mask" "B.Paste")
			(net "P0V9_CPU0_RT1_2A")
		)
		(pad "2" smd circle
			(at -0.40005 0 270)
			(size 0 0)
			(layers "B.Cu" "B.Mask" "B.Paste")
			(net "GND")
		)
	)
)
